(kicad_pcb
	(version 20260206)
	(generator "pcbnew")
	(generator_version "10.0")
	(general
		(thickness 1.6)
		(legacy_teardrops no)
	)
	(paper "A4")
	(title_block
		(title "03242023_DA0F0TMBIJ0_F0T_Motherboard_J_brd_V01_OCP.brd")
		(comment 1 "Grand Teton / footprint 1682 of 6105 (U1), pads 4108-4215 of 4677")
	)
	(layers
		(0 "F.Cu" signal "TOP")
		(4 "In1.Cu" signal "GND")
		(6 "In2.Cu" signal "IN1")
		(8 "In3.Cu" signal "GND1")
		(10 "In4.Cu" signal "IN2")
		(12 "In5.Cu" signal "GND2")
		(14 "In6.Cu" signal "IN3")
		(16 "In7.Cu" signal "GND3")
		(18 "In8.Cu" signal "VCC")
		(20 "In9.Cu" signal "VCC1")
		(22 "In10.Cu" signal "GND4")
		(24 "In11.Cu" signal "IN4")
		(26 "In12.Cu" signal "GND5")
		(28 "In13.Cu" signal "IN5")
		(30 "In14.Cu" signal "GND6")
		(32 "In15.Cu" signal "IN6")
		(34 "In16.Cu" signal "GND7")
		(2 "B.Cu" signal "BOTTOM")
		(9 "F.Adhes" user "F.Adhesive")
		(11 "B.Adhes" user "B.Adhesive")
		(13 "F.Paste" user "Package Geometry/Pastemask Top")
		(15 "B.Paste" user "Package Geometry/Pastemask Bottom")
		(5 "F.SilkS" user "Ref Des/Silkscreen Top")
		(7 "B.SilkS" user "Ref Des/Silkscreen Bottom")
		(1 "F.Mask" user "Board Geometry/Soldermask Top")
		(3 "B.Mask" user "Board Geometry/Soldermask Bottom")
		(17 "Dwgs.User" user "User.Drawings")
		(19 "Cmts.User" user "User.Comments")
		(21 "Eco1.User" user "User.Eco1")
		(23 "Eco2.User" user "User.Eco2")
		(25 "Edge.Cuts" user "Board Geometry/Outline")
		(27 "Margin" user)
		(31 "F.CrtYd" user "Package Geometry/Place Bound Top")
		(29 "B.CrtYd" user "Package Geometry/Place Bound Bottom")
		(35 "F.Fab" user "Ref Des/Assembly Top")
		(33 "B.Fab" user "Ref Des/Assembly Bottom")
	)
	(footprint ""
		(layer "F.Cu")
		(at 111.93018 -251.76988 90)
		(property "Reference" "U1"
			(at -74.913236 41.548812 0)
			(unlocked yes)
			(layer "F.SilkS")
			(effects
				(font
					(size 1.6002 1.1938)
					(thickness 0.1524)
				)
				(justify left)
			)
		)
		(property "Value" ""
			(at 0 0 90)
			(layer "F.Fab")
			(effects
				(font
					(size 1.27 1.27)
				)
			)
		)
		(duplicate_pad_numbers_are_jumpers no)
		(pad "H22" smd circle
			(at -20.333462 -23.784814 270)
			(size 0.4318 0.4318)
			(layers "F.Cu" "F.Mask" "F.Paste")
			(net "GND")
		)
		(pad "H24" smd circle
			(at -18.705576 -23.784814 270)
			(size 0.4318 0.4318)
			(layers "F.Cu" "F.Mask" "F.Paste")
			(net "M_B_CPU1_SB_DQS_DN<1>")
		)
		(pad "H26" smd circle
			(at -17.07769 -23.784814 270)
			(size 0.4318 0.4318)
			(layers "F.Cu" "F.Mask" "F.Paste")
			(net "GND")
		)
		(pad "H28" smd circle
			(at -15.450058 -23.784814 270)
			(size 0.4318 0.4318)
			(layers "F.Cu" "F.Mask" "F.Paste")
			(net "GND")
		)
		(pad "H30" smd circle
			(at -13.822426 -23.784814 270)
			(size 0.4318 0.4318)
			(layers "F.Cu" "F.Mask" "F.Paste")
			(net "M_A_CPU1_SB_DQS_DN<0>")
		)
		(pad "H32" smd circle
			(at -12.19454 -23.784814 270)
			(size 0.4318 0.4318)
			(layers "F.Cu" "F.Mask" "F.Paste")
			(net "GND")
		)
		(pad "H34" smd circle
			(at -10.566654 -23.784814 270)
			(size 0.4318 0.4318)
			(layers "F.Cu" "F.Mask" "F.Paste")
			(net "GND")
		)
		(pad "H36" smd circle
			(at -8.939022 -23.784814 270)
			(size 0.4318 0.4318)
			(layers "F.Cu" "F.Mask" "F.Paste")
			(net "M_B_CPU1_SB_DQS_DP<9>")
		)
		(pad "H38" smd circle
			(at -7.311136 -23.784814 270)
			(size 0.4318 0.4318)
			(layers "F.Cu" "F.Mask" "F.Paste")
			(net "GND")
		)
		(pad "H40" smd circle
			(at -5.68325 -23.784814 270)
			(size 0.4318 0.4318)
			(layers "F.Cu" "F.Mask" "F.Paste")
			(net "GND")
		)
		(pad "H42" smd circle
			(at -4.055618 -23.784814 270)
			(size 0.4318 0.4318)
			(layers "F.Cu" "F.Mask" "F.Paste")
			(net "M_B_CPU1_SB_CA<6>")
		)
		(pad "H44" smd circle
			(at -2.427732 -23.784814 270)
			(size 0.4318 0.4318)
			(layers "F.Cu" "F.Mask" "F.Paste")
			(net "GND")
		)
		(pad "H47" smd circle
			(at 1.613916 -23.675086 270)
			(size 0.4318 0.4318)
			(layers "F.Cu" "F.Mask" "F.Paste")
			(net "GND")
		)
		(pad "H49" smd circle
			(at 3.241802 -23.675086 270)
			(size 0.4318 0.4318)
			(layers "F.Cu" "F.Mask" "F.Paste")
			(net "M_B_CPU1_SA_CA<0>")
		)
		(pad "H51" smd circle
			(at 4.869434 -23.675086 270)
			(size 0.4318 0.4318)
			(layers "F.Cu" "F.Mask" "F.Paste")
			(net "GND")
		)
		(pad "H53" smd circle
			(at 6.49732 -23.675086 270)
			(size 0.4318 0.4318)
			(layers "F.Cu" "F.Mask" "F.Paste")
			(net "GND")
		)
		(pad "H55" smd circle
			(at 8.124952 -23.675086 270)
			(size 0.4318 0.4318)
			(layers "F.Cu" "F.Mask" "F.Paste")
			(net "M_B_CPU1_SA_DQS_DN<4>")
		)
		(pad "H57" smd circle
			(at 9.752838 -23.675086 270)
			(size 0.4318 0.4318)
			(layers "F.Cu" "F.Mask" "F.Paste")
			(net "GND")
		)
		(pad "H59" smd circle
			(at 11.380724 -23.675086 270)
			(size 0.4318 0.4318)
			(layers "F.Cu" "F.Mask" "F.Paste")
			(net "GND")
		)
		(pad "H61" smd circle
			(at 13.008356 -23.675086 270)
			(size 0.4318 0.4318)
			(layers "F.Cu" "F.Mask" "F.Paste")
			(net "M_B_CPU1_SA_DQS_DN<2>")
		)
		(pad "H63" smd circle
			(at 14.635988 -23.675086 270)
			(size 0.4318 0.4318)
			(layers "F.Cu" "F.Mask" "F.Paste")
			(net "GND")
		)
		(pad "H65" smd circle
			(at 16.263874 -23.675086 270)
			(size 0.4318 0.4318)
			(layers "F.Cu" "F.Mask" "F.Paste")
			(net "GND")
		)
		(pad "H67" smd circle
			(at 17.89176 -23.675086 270)
			(size 0.4318 0.4318)
			(layers "F.Cu" "F.Mask" "F.Paste")
			(net "M_A_CPU1_SA_DQS_DN<1>")
		)
		(pad "H69" smd circle
			(at 19.519392 -23.675086 270)
			(size 0.4318 0.4318)
			(layers "F.Cu" "F.Mask" "F.Paste")
			(net "GND")
		)
		(pad "H71" smd circle
			(at 21.147278 -23.675086 270)
			(size 0.4318 0.4318)
			(layers "F.Cu" "F.Mask" "F.Paste")
			(net "GND")
		)
		(pad "H73" smd circle
			(at 22.77491 -23.675086 270)
			(size 0.4318 0.4318)
			(layers "F.Cu" "F.Mask" "F.Paste")
			(net "M_B_CPU1_SA_DQS_DN<0>")
		)
		(pad "H75" smd circle
			(at 24.402796 -23.675086 270)
			(size 0.4318 0.4318)
			(layers "F.Cu" "F.Mask" "F.Paste")
			(net "GND")
		)
		(pad "H77" smd circle
			(at 26.030682 -23.675086 270)
			(size 0.4318 0.4318)
			(layers "F.Cu" "F.Mask" "F.Paste")
			(net "M_A_CPU1_SA_DQS_DN<5>")
		)
		(pad "H79" smd circle
			(at 27.658314 -23.675086 270)
			(size 0.4318 0.4318)
			(layers "F.Cu" "F.Mask" "F.Paste")
			(net "GND")
		)
		(pad "H81" smd circle
			(at 29.2862 -23.675086 270)
			(size 0.4318 0.4318)
			(layers "F.Cu" "F.Mask" "F.Paste")
			(net "GND")
		)
		(pad "H83" smd circle
			(at 30.914086 -23.675086 270)
			(size 0.4318 0.4318)
			(layers "F.Cu" "F.Mask" "F.Paste")
			(net "UPI_CPU0_CPU1_P2P2_DP<2>")
		)
		(pad "H85" smd circle
			(at 32.541718 -23.675086 270)
			(size 0.4318 0.4318)
			(layers "F.Cu" "F.Mask" "F.Paste")
			(net "UPI_CPU1_CPU0_P2P2_DN<4>")
		)
		(pad "H87" smd circle
			(at 34.169604 -23.675086 270)
			(size 0.4318 0.4318)
			(layers "F.Cu" "F.Mask" "F.Paste")
			(net "UPI_CPU1_CPU0_P2P2_DP<3>")
		)
		(pad "H89" smd oval
			(at 35.797236 -23.675086 45)
			(size 0.381 0.4826)
			(drill
				(offset 0 -0.0508)
			)
			(layers "F.Cu" "F.Mask" "F.Paste")
			(net "PVCCFA_EHV_FIVRA_CPU1")
		)
		(pad "J3" smd oval
			(at -35.797236 -23.314914 135)
			(size 0.381 0.4826)
			(drill
				(offset 0 -0.0508)
			)
			(layers "F.Cu" "F.Mask" "F.Paste")
			(net "UPI_CPU1_CPU0_P0P1_DP<0>")
		)
		(pad "J5" smd circle
			(at -34.169604 -23.314914 270)
			(size 0.4318 0.4318)
			(layers "F.Cu" "F.Mask" "F.Paste")
			(net "GND")
		)
		(pad "J7" smd circle
			(at -32.541718 -23.314914 270)
			(size 0.4318 0.4318)
			(layers "F.Cu" "F.Mask" "F.Paste")
			(net "PVCCFA_EHV_FIVRA_CPU1")
		)
		(pad "J9" smd circle
			(at -30.914086 -23.314914 270)
			(size 0.4318 0.4318)
			(layers "F.Cu" "F.Mask" "F.Paste")
			(net "GND")
		)
		(pad "J11" smd circle
			(at -29.2862 -23.314914 270)
			(size 0.4318 0.4318)
			(layers "F.Cu" "F.Mask" "F.Paste")
			(net "PVCCFA_EHV_FIVRA_CPU1")
		)
		(pad "J13" smd circle
			(at -27.658314 -23.314914 270)
			(size 0.4318 0.4318)
			(layers "F.Cu" "F.Mask" "F.Paste")
			(net "TP_CPU1_PPD")
		)
		(pad "J15" smd circle
			(at -26.030682 -23.314914 270)
			(size 0.4318 0.4318)
			(layers "F.Cu" "F.Mask" "F.Paste")
			(net "GND")
		)
		(pad "J17" smd circle
			(at -24.402796 -23.314914 270)
			(size 0.4318 0.4318)
			(layers "F.Cu" "F.Mask" "F.Paste")
			(net "M_B_CPU1_SB_DQ<20>")
		)
		(pad "J19" smd circle
			(at -22.77491 -23.314914 270)
			(size 0.4318 0.4318)
			(layers "F.Cu" "F.Mask" "F.Paste")
			(net "M_B_CPU1_SB_DQ<17>")
		)
		(pad "J21" smd circle
			(at -21.147278 -23.314914 270)
			(size 0.4318 0.4318)
			(layers "F.Cu" "F.Mask" "F.Paste")
			(net "GND")
		)
		(pad "J23" smd circle
			(at -19.519392 -23.314914 270)
			(size 0.4318 0.4318)
			(layers "F.Cu" "F.Mask" "F.Paste")
			(net "M_B_CPU1_SB_DQ<12>")
		)
		(pad "J25" smd circle
			(at -17.89176 -23.314914 270)
			(size 0.4318 0.4318)
			(layers "F.Cu" "F.Mask" "F.Paste")
			(net "M_B_CPU1_SB_DQ<9>")
		)
		(pad "J27" smd circle
			(at -16.263874 -23.314914 270)
			(size 0.4318 0.4318)
			(layers "F.Cu" "F.Mask" "F.Paste")
			(net "GND")
		)
		(pad "J29" smd circle
			(at -14.635988 -23.314914 270)
			(size 0.4318 0.4318)
			(layers "F.Cu" "F.Mask" "F.Paste")
			(net "M_A_CPU1_SB_DQ<4>")
		)
		(pad "J31" smd circle
			(at -13.008356 -23.314914 270)
			(size 0.4318 0.4318)
			(layers "F.Cu" "F.Mask" "F.Paste")
			(net "M_A_CPU1_SB_DQ<1>")
		)
		(pad "J33" smd circle
			(at -11.380724 -23.314914 270)
			(size 0.4318 0.4318)
			(layers "F.Cu" "F.Mask" "F.Paste")
			(net "GND")
		)
		(pad "J35" smd circle
			(at -9.752838 -23.314914 270)
			(size 0.4318 0.4318)
			(layers "F.Cu" "F.Mask" "F.Paste")
			(net "M_B_CPU1_SB_CB<0>")
		)
		(pad "J37" smd circle
			(at -8.124952 -23.314914 270)
			(size 0.4318 0.4318)
			(layers "F.Cu" "F.Mask" "F.Paste")
			(net "M_B_CPU1_SB_CB<5>")
		)
		(pad "J39" smd circle
			(at -6.49732 -23.314914 270)
			(size 0.4318 0.4318)
			(layers "F.Cu" "F.Mask" "F.Paste")
			(net "GND")
		)
		(pad "J41" smd circle
			(at -4.869434 -23.314914 270)
			(size 0.4318 0.4318)
			(layers "F.Cu" "F.Mask" "F.Paste")
			(net "M_B_CPU1_SB_CS_N<0>")
		)
		(pad "J43" smd circle
			(at -3.241802 -23.314914 270)
			(size 0.4318 0.4318)
			(layers "F.Cu" "F.Mask" "F.Paste")
			(net "M_B_CPU1_SB_CA<4>")
		)
		(pad "J45" smd circle
			(at -1.613916 -23.314914 270)
			(size 0.4318 0.4318)
			(layers "F.Cu" "F.Mask" "F.Paste")
			(net "GND")
		)
		(pad "J48" smd circle
			(at 2.427732 -23.204932 270)
			(size 0.4318 0.4318)
			(layers "F.Cu" "F.Mask" "F.Paste")
			(net "M_B_CPU1_SA_CA<2>")
		)
		(pad "J50" smd circle
			(at 4.055618 -23.204932 270)
			(size 0.4318 0.4318)
			(layers "F.Cu" "F.Mask" "F.Paste")
			(net "M_B_CPU1_SA_CS_N<1>")
		)
		(pad "J52" smd circle
			(at 5.68325 -23.204932 270)
			(size 0.4318 0.4318)
			(layers "F.Cu" "F.Mask" "F.Paste")
			(net "GND")
		)
		(pad "J54" smd circle
			(at 7.311136 -23.204932 270)
			(size 0.4318 0.4318)
			(layers "F.Cu" "F.Mask" "F.Paste")
			(net "M_B_CPU1_SA_CB<4>")
		)
		(pad "J56" smd circle
			(at 8.939022 -23.204932 270)
			(size 0.4318 0.4318)
			(layers "F.Cu" "F.Mask" "F.Paste")
			(net "M_B_CPU1_SA_CB<1>")
		)
		(pad "J58" smd circle
			(at 10.566654 -23.204932 270)
			(size 0.4318 0.4318)
			(layers "F.Cu" "F.Mask" "F.Paste")
			(net "GND")
		)
		(pad "J60" smd circle
			(at 12.19454 -23.204932 270)
			(size 0.4318 0.4318)
			(layers "F.Cu" "F.Mask" "F.Paste")
			(net "M_B_CPU1_SA_DQ<20>")
		)
		(pad "J62" smd circle
			(at 13.822426 -23.204932 270)
			(size 0.4318 0.4318)
			(layers "F.Cu" "F.Mask" "F.Paste")
			(net "M_B_CPU1_SA_DQ<17>")
		)
		(pad "J64" smd circle
			(at 15.450058 -23.204932 270)
			(size 0.4318 0.4318)
			(layers "F.Cu" "F.Mask" "F.Paste")
			(net "GND")
		)
		(pad "J66" smd circle
			(at 17.07769 -23.204932 270)
			(size 0.4318 0.4318)
			(layers "F.Cu" "F.Mask" "F.Paste")
			(net "M_A_CPU1_SA_DQ<12>")
		)
		(pad "J68" smd circle
			(at 18.705576 -23.204932 270)
			(size 0.4318 0.4318)
			(layers "F.Cu" "F.Mask" "F.Paste")
			(net "M_A_CPU1_SA_DQ<9>")
		)
		(pad "J70" smd circle
			(at 20.333462 -23.204932 270)
			(size 0.4318 0.4318)
			(layers "F.Cu" "F.Mask" "F.Paste")
			(net "GND")
		)
		(pad "J72" smd circle
			(at 21.961094 -23.204932 270)
			(size 0.4318 0.4318)
			(layers "F.Cu" "F.Mask" "F.Paste")
			(net "M_B_CPU1_SA_DQ<4>")
		)
		(pad "J74" smd circle
			(at 23.58898 -23.204932 270)
			(size 0.4318 0.4318)
			(layers "F.Cu" "F.Mask" "F.Paste")
			(net "M_B_CPU1_SA_DQ<1>")
		)
		(pad "J76" smd circle
			(at 25.216612 -23.204932 270)
			(size 0.4318 0.4318)
			(layers "F.Cu" "F.Mask" "F.Paste")
			(net "GND")
		)
		(pad "J78" smd circle
			(at 26.844498 -23.204932 270)
			(size 0.4318 0.4318)
			(layers "F.Cu" "F.Mask" "F.Paste")
			(net "GND")
		)
		(pad "J80" smd circle
			(at 28.472384 -23.204932 270)
			(size 0.4318 0.4318)
			(layers "F.Cu" "F.Mask" "F.Paste")
			(net "PVCCFA_EHV_FIVRA_CPU1")
		)
		(pad "J82" smd circle
			(at 30.100016 -23.204932 270)
			(size 0.4318 0.4318)
			(layers "F.Cu" "F.Mask" "F.Paste")
			(net "UPI_CPU0_CPU1_P2P2_DN<4>")
		)
		(pad "J84" smd circle
			(at 31.727902 -23.204932 270)
			(size 0.4318 0.4318)
			(layers "F.Cu" "F.Mask" "F.Paste")
			(net "GND")
		)
		(pad "J86" smd circle
			(at 33.355534 -23.204932 270)
			(size 0.4318 0.4318)
			(layers "F.Cu" "F.Mask" "F.Paste")
			(net "GND")
		)
		(pad "J88" smd circle
			(at 34.98342 -23.204932 270)
			(size 0.4318 0.4318)
			(layers "F.Cu" "F.Mask" "F.Paste")
			(net "GND")
		)
		(pad "J90" smd oval
			(at 36.611306 -23.204932 45)
			(size 0.381 0.4826)
			(drill
				(offset 0 -0.0508)
			)
			(layers "F.Cu" "F.Mask" "F.Paste")
			(net "P5E_CPU1_PE4_RX_DN<0>")
		)
		(pad "K2" smd oval
			(at -36.611306 -22.845268 135)
			(size 0.381 0.4826)
			(drill
				(offset 0 -0.0508)
			)
			(layers "F.Cu" "F.Mask" "F.Paste")
			(net "GND")
		)
		(pad "K4" smd circle
			(at -34.98342 -22.845268 270)
			(size 0.4318 0.4318)
			(layers "F.Cu" "F.Mask" "F.Paste")
			(net "UPI_CPU1_CPU0_P0P1_DN<0>")
		)
		(pad "K6" smd circle
			(at -33.355534 -22.845268 270)
			(size 0.4318 0.4318)
			(layers "F.Cu" "F.Mask" "F.Paste")
			(net "UPI_CPU0_CPU1_P1P0_DN<0>")
		)
		(pad "K8" smd circle
			(at -31.727902 -22.845268 270)
			(size 0.4318 0.4318)
			(layers "F.Cu" "F.Mask" "F.Paste")
			(net "GND")
		)
		(pad "K10" smd circle
			(at -30.100016 -22.845268 270)
			(size 0.4318 0.4318)
			(layers "F.Cu" "F.Mask" "F.Paste")
			(net "P5E_CPU1_PE0_RX_DN<0>")
		)
		(pad "K12" smd circle
			(at -28.472384 -22.845268 270)
			(size 0.4318 0.4318)
			(layers "F.Cu" "F.Mask" "F.Paste")
			(net "GND")
		)
		(pad "K14" smd circle
			(at -26.844498 -22.845268 270)
			(size 0.4318 0.4318)
			(layers "F.Cu" "F.Mask" "F.Paste")
			(net "GND")
		)
		(pad "K16" smd circle
			(at -25.216612 -22.845268 270)
			(size 0.4318 0.4318)
			(layers "F.Cu" "F.Mask" "F.Paste")
			(net "M_B_CPU1_SB_DQ<21>")
		)
		(pad "K18" smd circle
			(at -23.58898 -22.845268 270)
			(size 0.4318 0.4318)
			(layers "F.Cu" "F.Mask" "F.Paste")
			(net "M_B_CPU1_SB_DQS_DP<2>")
		)
		(pad "K20" smd circle
			(at -21.961094 -22.845268 270)
			(size 0.4318 0.4318)
			(layers "F.Cu" "F.Mask" "F.Paste")
			(net "M_B_CPU1_SB_DQ<16>")
		)
		(pad "K22" smd circle
			(at -20.333462 -22.845268 270)
			(size 0.4318 0.4318)
			(layers "F.Cu" "F.Mask" "F.Paste")
			(net "M_B_CPU1_SB_DQ<13>")
		)
		(pad "K24" smd circle
			(at -18.705576 -22.845268 270)
			(size 0.4318 0.4318)
			(layers "F.Cu" "F.Mask" "F.Paste")
			(net "M_B_CPU1_SB_DQS_DP<1>")
		)
		(pad "K26" smd circle
			(at -17.07769 -22.845268 270)
			(size 0.4318 0.4318)
			(layers "F.Cu" "F.Mask" "F.Paste")
			(net "M_B_CPU1_SB_DQ<8>")
		)
		(pad "K28" smd circle
			(at -15.450058 -22.845268 270)
			(size 0.4318 0.4318)
			(layers "F.Cu" "F.Mask" "F.Paste")
			(net "M_A_CPU1_SB_DQ<5>")
		)
		(pad "K30" smd circle
			(at -13.822426 -22.845268 270)
			(size 0.4318 0.4318)
			(layers "F.Cu" "F.Mask" "F.Paste")
			(net "M_A_CPU1_SB_DQS_DP<0>")
		)
		(pad "K32" smd circle
			(at -12.19454 -22.845268 270)
			(size 0.4318 0.4318)
			(layers "F.Cu" "F.Mask" "F.Paste")
			(net "M_A_CPU1_SB_DQ<0>")
		)
		(pad "K34" smd circle
			(at -10.566654 -22.845268 270)
			(size 0.4318 0.4318)
			(layers "F.Cu" "F.Mask" "F.Paste")
			(net "M_B_CPU1_SB_CB<1>")
		)
		(pad "K36" smd circle
			(at -8.939022 -22.845268 270)
			(size 0.4318 0.4318)
			(layers "F.Cu" "F.Mask" "F.Paste")
			(net "M_B_CPU1_SB_DQS_DN<9>")
		)
		(pad "K38" smd circle
			(at -7.311136 -22.845268 270)
			(size 0.4318 0.4318)
			(layers "F.Cu" "F.Mask" "F.Paste")
			(net "M_B_CPU1_SB_CB<4>")
		)
		(pad "K40" smd circle
			(at -5.68325 -22.845268 270)
			(size 0.4318 0.4318)
			(layers "F.Cu" "F.Mask" "F.Paste")
			(net "M_B_CPU1_SB_CS_N<1>")
		)
		(pad "K42" smd circle
			(at -4.055618 -22.845268 270)
			(size 0.4318 0.4318)
			(layers "F.Cu" "F.Mask" "F.Paste")
			(net "GND")
		)
		(pad "K44" smd circle
			(at -2.427732 -22.845268 270)
			(size 0.4318 0.4318)
			(layers "F.Cu" "F.Mask" "F.Paste")
			(net "M_B_CPU1_SB_CA<2>")
		)
		(pad "K47" smd circle
			(at 1.613916 -22.735286 270)
			(size 0.4318 0.4318)
			(layers "F.Cu" "F.Mask" "F.Paste")
			(net "M_B_CPU1_SA_CA<4>")
		)
		(pad "K49" smd circle
			(at 3.241802 -22.735286 270)
			(size 0.4318 0.4318)
			(layers "F.Cu" "F.Mask" "F.Paste")
			(net "GND")
		)
		(pad "K51" smd circle
			(at 4.869434 -22.735286 270)
			(size 0.4318 0.4318)
			(layers "F.Cu" "F.Mask" "F.Paste")
			(net "M_B_CPU1_SA_CS_N<0>")
		)
		(pad "K53" smd circle
			(at 6.49732 -22.735286 270)
			(size 0.4318 0.4318)
			(layers "F.Cu" "F.Mask" "F.Paste")
			(net "M_B_CPU1_SA_CB<5>")
		)
		(pad "K55" smd circle
			(at 8.124952 -22.735286 270)
			(size 0.4318 0.4318)
			(layers "F.Cu" "F.Mask" "F.Paste")
			(net "M_B_CPU1_SA_DQS_DP<4>")
		)
		(pad "K57" smd circle
			(at 9.752838 -22.735286 270)
			(size 0.4318 0.4318)
			(layers "F.Cu" "F.Mask" "F.Paste")
			(net "M_B_CPU1_SA_CB<0>")
		)
		(pad "K59" smd circle
			(at 11.380724 -22.735286 270)
			(size 0.4318 0.4318)
			(layers "F.Cu" "F.Mask" "F.Paste")
			(net "M_B_CPU1_SA_DQ<21>")
		)
		(pad "K61" smd circle
			(at 13.008356 -22.735286 270)
			(size 0.4318 0.4318)
			(layers "F.Cu" "F.Mask" "F.Paste")
			(net "M_B_CPU1_SA_DQS_DP<2>")
		)
	)
)
